(kicad_pcb
	(version 20221018)
	(generator pcbnew)
	(general
    (thickness 0.908)
  )
	(paper "A4")
	(title_block
    (title "HDMI-MIPI Bridge")
    (date "2024-04-24")
    (rev "1.3.2")
		(comment 9 "footprints 90-90 of 121")
	)
	(layers
    (0 "F.Cu" signal)
    (1 "In1.Cu" signal)
    (2 "In2.Cu" signal)
    (31 "B.Cu" signal)
    (32 "B.Adhes" user "B.Adhesive")
    (33 "F.Adhes" user "F.Adhesive")
    (34 "B.Paste" user)
    (35 "F.Paste" user)
    (36 "B.SilkS" user "B.Silkscreen")
    (37 "F.SilkS" user "F.Silkscreen")
    (38 "B.Mask" user)
    (39 "F.Mask" user)
    (40 "Dwgs.User" user "User.Drawings")
    (41 "Cmts.User" user "User.Comments")
    (42 "Eco1.User" user "User.Eco1")
    (43 "Eco2.User" user "User.Eco2")
    (44 "Edge.Cuts" user)
    (45 "Margin" user)
    (46 "B.CrtYd" user "B.Courtyard")
    (47 "F.CrtYd" user "F.Courtyard")
    (48 "B.Fab" user)
    (49 "F.Fab" user)
  )
	(footprint "antmicro-footprints:BGA-64_8x8_6.0x6.0mm" locked (layer "F.Cu")
    (at 159.425 110.45 -90)
    (property "Author" "Antmicro")
    (property "License" "Apache-2.0")
    (property "MPN" "TC358743XBG")
    (property "Manufacturer" "Toshiba")
    (property "Sheetfile" "channel2.kicad_sch")
    (property "Sheetname" "Channel 2")
    (property "ki_description" "HDMI to MIPI CSI-2 bridge. Supports HDMI 1.4. MIPI CSI-2 compliant. 80-Pin VFBGA")
    (property "ki_keywords" "SMT, INTERFACE, IC, CONTROLLER")
    (attr smd)
    (fp_text reference "U4" (at -3.45 3.325) (layer "F.SilkS")
        (effects (font (size 0.65 0.65) (thickness 0.13)) (justify left bottom))
    )
    (fp_text value "TC358743XBG" (at -7.0104 4.8768 -90) (layer "F.Fab")
        (effects (font (size 0.65 0.65) (thickness 0.13)) (justify left bottom))
    )
    (fp_text user "Author: Antmicro" (at -9 7.2 -90) (layer "F.Fab") hide
        (effects (font (size 0.7 0.7) (thickness 0.15)) (justify left bottom))
    )
    (fp_text user "${REFERENCE}" (at -9 5.999 -90) (layer "F.Fab") hide
        (effects (font (size 0.7 0.7) (thickness 0.15)) (justify left bottom))
    )
    (fp_text user "License: Apache-2.0" (at -9 8.4 -90) (layer "F.Fab") hide
        (effects (font (size 0.7 0.7) (thickness 0.15)) (justify left bottom))
    )
    (fp_line (start -3.121 -2) (end -3.121 -1.621)
      (stroke (width 0.15) (type solid)) (layer "F.SilkS"))
    (fp_line (start -3.121 3.12) (end -3.121 1.62)
      (stroke (width 0.15) (type solid)) (layer "F.SilkS"))
    (fp_line (start -2 -3.121) (end -3.121 -2)
      (stroke (width 0.15) (type solid)) (layer "F.SilkS"))
    (fp_line (start -1.621 -3.121) (end -2 -3.121)
      (stroke (width 0.15) (type solid)) (layer "F.SilkS"))
    (fp_line (start -1.621 3.12) (end -3.121 3.12)
      (stroke (width 0.15) (type solid)) (layer "F.SilkS"))
    (fp_line (start 1.62 -3.121) (end 3.12 -3.121)
      (stroke (width 0.15) (type solid)) (layer "F.SilkS"))
    (fp_line (start 1.62 -3.121) (end 3.12 -3.121)
      (stroke (width 0.15) (type solid)) (layer "F.SilkS"))
    (fp_line (start 1.62 -3.121) (end 3.12 -3.121)
      (stroke (width 0.15) (type solid)) (layer "F.SilkS"))
    (fp_line (start 1.62 3.12) (end 3.12 3.12)
      (stroke (width 0.15) (type solid)) (layer "F.SilkS"))
    (fp_line (start 3.12 -3.121) (end 3.12 -1.621)
      (stroke (width 0.15) (type solid)) (layer "F.SilkS"))
    (fp_line (start 3.12 -3.121) (end 3.12 -1.621)
      (stroke (width 0.15) (type solid)) (layer "F.SilkS"))
    (fp_line (start 3.12 -3.121) (end 3.12 -1.621)
      (stroke (width 0.15) (type solid)) (layer "F.SilkS"))
    (fp_line (start 3.12 3.12) (end 3.12 1.62)
      (stroke (width 0.15) (type solid)) (layer "F.SilkS"))
    (fp_circle (center -3 -2.9954) (end -2.951 -2.9954)
      (stroke (width 0.15) (type solid)) (fill solid) (layer "F.SilkS"))
    (fp_line (start -3.21 -3.21) (end 3.2 -3.21)
      (stroke (width 0.05) (type solid)) (layer "F.CrtYd"))
    (fp_line (start -3.21 3.2) (end -3.21 -3.21)
      (stroke (width 0.05) (type solid)) (layer "F.CrtYd"))
    (fp_line (start 3.2 -3.21) (end 3.2 3.2)
      (stroke (width 0.05) (type solid)) (layer "F.CrtYd"))
    (fp_line (start 3.2 3.2) (end -3.21 3.2)
      (stroke (width 0.05) (type solid)) (layer "F.CrtYd"))
    (fp_line (start -3 -2) (end -3 2.999)
      (stroke (width 0.15) (type solid)) (layer "F.Fab"))
    (fp_line (start -3 2.999) (end 2.999 2.999)
      (stroke (width 0.15) (type solid)) (layer "F.Fab"))
    (fp_line (start -2 -3) (end -3 -2)
      (stroke (width 0.15) (type solid)) (layer "F.Fab"))
    (fp_line (start 2.999 -3) (end -2 -3)
      (stroke (width 0.15) (type solid)) (layer "F.Fab"))
    (fp_line (start 2.999 2.999) (end 2.999 -3)
      (stroke (width 0.15) (type solid)) (layer "F.Fab"))
    (pad "A1" smd circle locked (at -2.275 -2.275 270) (size 0.3 0.3) (layers "F.Cu" "F.Paste" "F.Mask")
      (net 114 "Net-(U4B-REXT)") (pinfunction "REXT") (pintype "input"))
    (pad "A2" smd circle locked (at -1.625 -2.275 270) (size 0.3 0.3) (layers "F.Cu" "F.Paste" "F.Mask")
      (net 2 "GND") (pinfunction "GND") (pintype "power_in"))
    (pad "A3" smd circle locked (at -0.975 -2.275 270) (size 0.3 0.3) (layers "F.Cu" "F.Paste" "F.Mask")
      (net 2 "GND") (pinfunction "VPGM") (pintype "input"))
    (pad "A4" smd circle locked (at -0.326 -2.275 270) (size 0.3 0.3) (layers "F.Cu" "F.Paste" "F.Mask")
      (net 16 "Net-(U4C-BIASDA)") (pinfunction "BIASDA") (pintype "output"))
    (pad "A5" smd circle locked (at 0.325 -2.275 270) (size 0.3 0.3) (layers "F.Cu" "F.Paste" "F.Mask")
      (net 17 "Net-(U4C-DAOUT)") (pinfunction "DAOUT") (pintype "output"))
    (pad "A6" smd circle locked (at 0.974 -2.275 270) (size 0.3 0.3) (layers "F.Cu" "F.Paste" "F.Mask")
      (net 131 "unconnected-(U4C-PFIL-PadA6)") (pinfunction "PFIL") (pintype "output+no_connect"))
    (pad "A7" smd circle locked (at 1.624 -2.275 270) (size 0.3 0.3) (layers "F.Cu" "F.Paste" "F.Mask")
      (net 34 "CSI3_D4_N") (pinfunction "CSID3_N") (pintype "output"))
    (pad "A8" smd circle locked (at 2.274 -2.275 270) (size 0.3 0.3) (layers "F.Cu" "F.Paste" "F.Mask")
      (net 35 "CSI3_D4_P") (pinfunction "CSID3_P") (pintype "output"))
    (pad "B1" smd circle locked (at -2.275 -1.625 270) (size 0.3 0.3) (layers "F.Cu" "F.Paste" "F.Mask")
      (net 108 "/Channel 2/CH2_AVDD33") (pinfunction "AVDD33") (pintype "power_in"))
    (pad "B2" smd circle locked (at -1.625 -1.625 270) (size 0.3 0.3) (layers "F.Cu" "F.Paste" "F.Mask")
      (net 109 "Net-(C48-Pad1)") (pinfunction "AVDD12") (pintype "power_in"))
    (pad "B3" smd circle locked (at -0.975 -1.625 270) (size 0.3 0.3) (layers "F.Cu" "F.Paste" "F.Mask")
      (net 132 "unconnected-(U4B-INT-PadB3)") (pinfunction "INT") (pintype "output+no_connect"))
    (pad "B4" smd circle locked (at -0.326 -1.625 270) (size 0.3 0.3) (layers "F.Cu" "F.Paste" "F.Mask")
      (net 133 "unconnected-(U4A-IR-PadB4)") (pinfunction "IR") (pintype "input+no_connect"))
    (pad "B5" smd circle locked (at 0.325 -1.625 270) (size 0.3 0.3) (layers "F.Cu" "F.Paste" "F.Mask")
      (net 32 "Net-(U4B-AVDD25)") (pinfunction "AVDD25") (pintype "power_in"))
    (pad "B6" smd circle locked (at 0.974 -1.625 270) (size 0.3 0.3) (layers "F.Cu" "F.Paste" "F.Mask")
      (net 18 "Net-(U4C-PCKIN)") (pinfunction "PCKIN") (pintype "input"))
    (pad "B7" smd circle locked (at 1.624 -1.625 270) (size 0.3 0.3) (layers "F.Cu" "F.Paste" "F.Mask")
      (net 36 "CSI3_D3_N") (pinfunction "CSID2_N") (pintype "output"))
    (pad "B8" smd circle locked (at 2.274 -1.625 270) (size 0.3 0.3) (layers "F.Cu" "F.Paste" "F.Mask")
      (net 37 "CSI3_D3_P") (pinfunction "CSID2_P") (pintype "output"))
    (pad "C1" smd circle locked (at -2.275 -0.975 270) (size 0.3 0.3) (layers "F.Cu" "F.Paste" "F.Mask")
      (net 94 "/Channel 2/HDMI2_CLK_P") (pinfunction "HDMIC_P") (pintype "input"))
    (pad "C2" smd circle locked (at -1.625 -0.975 270) (size 0.3 0.3) (layers "F.Cu" "F.Paste" "F.Mask")
      (net 137 "/Channel 2/HDMI2_CLK_N") (pinfunction "HDMIC_N") (pintype "input"))
    (pad "C3" smd circle locked (at -0.975 -0.975 270) (size 0.3 0.3) (layers "F.Cu" "F.Paste" "F.Mask")
      (net 22 "Net-(C31-Pad2)") (pinfunction "VDDC2") (pintype "power_in"))
    (pad "C4" smd circle locked (at -0.326 -0.975 270) (size 0.3 0.3) (layers "F.Cu" "F.Paste" "F.Mask")
      (net 2 "GND") (pinfunction "GND") (pintype "passive"))
    (pad "C5" smd circle locked (at 0.325 -0.975 270) (size 0.3 0.3) (layers "F.Cu" "F.Paste" "F.Mask")
      (net 2 "GND") (pinfunction "GND") (pintype "passive"))
    (pad "C6" smd circle locked (at 0.974 -0.975 270) (size 0.3 0.3) (layers "F.Cu" "F.Paste" "F.Mask")
      (net 110 "Net-(C49-Pad1)") (pinfunction "VDD_MIPI") (pintype "power_in"))
    (pad "C7" smd circle locked (at 1.624 -0.975 270) (size 0.3 0.3) (layers "F.Cu" "F.Paste" "F.Mask")
      (net 42 "CSI3_CLK_N") (pinfunction "CSIC_N") (pintype "output"))
    (pad "C8" smd circle locked (at 2.274 -0.975 270) (size 0.3 0.3) (layers "F.Cu" "F.Paste" "F.Mask")
      (net 43 "CSI3_CLK_P") (pinfunction "CSIC_P") (pintype "output"))
    (pad "D1" smd circle locked (at -2.275 -0.326 270) (size 0.3 0.3) (layers "F.Cu" "F.Paste" "F.Mask")
      (net 92 "/Channel 2/HDMI2_D0_P") (pinfunction "HDMID0_P") (pintype "input"))
    (pad "D2" smd circle locked (at -1.625 -0.326 270) (size 0.3 0.3) (layers "F.Cu" "F.Paste" "F.Mask")
      (net 93 "/Channel 2/HDMI2_D0_N") (pinfunction "HDMID0_N") (pintype "input"))
    (pad "D3" smd circle locked (at -0.975 -0.326 270) (size 0.3 0.3) (layers "F.Cu" "F.Paste" "F.Mask")
      (net 109 "Net-(C48-Pad1)") (pinfunction "AVDD12") (pintype "passive"))
    (pad "D4" smd circle locked (at -0.326 -0.326 270) (size 0.3 0.3) (layers "F.Cu" "F.Paste" "F.Mask")
      (net 2 "GND") (pinfunction "GND") (pintype "passive"))
    (pad "D5" smd circle locked (at 0.325 -0.326 270) (size 0.3 0.3) (layers "F.Cu" "F.Paste" "F.Mask")
      (net 2 "GND") (pinfunction "GND") (pintype "passive"))
    (pad "D6" smd circle locked (at 0.974 -0.326 270) (size 0.3 0.3) (layers "F.Cu" "F.Paste" "F.Mask")
      (net 2 "GND") (pinfunction "GND") (pintype "passive"))
    (pad "D7" smd circle locked (at 1.624 -0.326 270) (size 0.3 0.3) (layers "F.Cu" "F.Paste" "F.Mask")
      (net 38 "CSI3_D2_N") (pinfunction "CSID1_N") (pintype "output"))
    (pad "D8" smd circle locked (at 2.274 -0.326 270) (size 0.3 0.3) (layers "F.Cu" "F.Paste" "F.Mask")
      (net 39 "CSI3_D2_P") (pinfunction "CSID1_P") (pintype "output"))
    (pad "E1" smd circle locked (at -2.275 0.325 270) (size 0.3 0.3) (layers "F.Cu" "F.Paste" "F.Mask")
      (net 90 "/Channel 2/HDMI2_D1_P") (pinfunction "HDMID1_P") (pintype "input"))
    (pad "E2" smd circle locked (at -1.625 0.325 270) (size 0.3 0.3) (layers "F.Cu" "F.Paste" "F.Mask")
      (net 91 "/Channel 2/HDMI2_D1_N") (pinfunction "HDMID1_N") (pintype "input"))
    (pad "E3" smd circle locked (at -0.975 0.325 270) (size 0.3 0.3) (layers "F.Cu" "F.Paste" "F.Mask")
      (net 2 "GND") (pinfunction "GND") (pintype "passive"))
    (pad "E4" smd circle locked (at -0.326 0.325 270) (size 0.3 0.3) (layers "F.Cu" "F.Paste" "F.Mask")
      (net 2 "GND") (pinfunction "GND") (pintype "passive"))
    (pad "E5" smd circle locked (at 0.325 0.325 270) (size 0.3 0.3) (layers "F.Cu" "F.Paste" "F.Mask")
      (net 2 "GND") (pinfunction "TEST") (pintype "input"))
    (pad "E6" smd circle locked (at 0.974 0.325 270) (size 0.3 0.3) (layers "F.Cu" "F.Paste" "F.Mask")
      (net 2 "GND") (pinfunction "GND") (pintype "passive"))
    (pad "E7" smd circle locked (at 1.624 0.325 270) (size 0.3 0.3) (layers "F.Cu" "F.Paste" "F.Mask")
      (net 40 "CSI3_D1_N") (pinfunction "CSID0_N") (pintype "output"))
    (pad "E8" smd circle locked (at 2.274 0.325 270) (size 0.3 0.3) (layers "F.Cu" "F.Paste" "F.Mask")
      (net 41 "CSI3_D1_P") (pinfunction "CSID0_P") (pintype "output"))
    (pad "F1" smd circle locked (at -2.275 0.974 270) (size 0.3 0.3) (layers "F.Cu" "F.Paste" "F.Mask")
      (net 88 "/Channel 2/HDMI2_D2_P") (pinfunction "HDMID2_P") (pintype "input"))
    (pad "F2" smd circle locked (at -1.625 0.974 270) (size 0.3 0.3) (layers "F.Cu" "F.Paste" "F.Mask")
      (net 89 "/Channel 2/HDMI2_D2_N") (pinfunction "HDMID2_N") (pintype "input"))
    (pad "F3" smd circle locked (at -0.975 0.974 270) (size 0.3 0.3) (layers "F.Cu" "F.Paste" "F.Mask")
      (net 108 "/Channel 2/CH2_AVDD33") (pinfunction "AVDD33") (pintype "passive"))
    (pad "F4" smd circle locked (at -0.326 0.974 270) (size 0.3 0.3) (layers "F.Cu" "F.Paste" "F.Mask")
      (net 23 "Net-(U4B-VDDIO1)") (pinfunction "VDDIO1") (pintype "power_in"))
    (pad "F5" smd circle locked (at 0.325 0.974 270) (size 0.3 0.3) (layers "F.Cu" "F.Paste" "F.Mask")
      (net 22 "Net-(C31-Pad2)") (pinfunction "VDDC2") (pintype "passive"))
    (pad "F6" smd circle locked (at 0.974 0.974 270) (size 0.3 0.3) (layers "F.Cu" "F.Paste" "F.Mask")
      (net 110 "Net-(C49-Pad1)") (pinfunction "VDD_MIPI") (pintype "passive"))
    (pad "F7" smd circle locked (at 1.624 0.974 270) (size 0.3 0.3) (layers "F.Cu" "F.Paste" "F.Mask")
      (net 134 "unconnected-(U4C-A_SCK-PadF7)") (pinfunction "A_SCK") (pintype "output+no_connect"))
    (pad "F8" smd circle locked (at 2.274 0.974 270) (size 0.3 0.3) (layers "F.Cu" "F.Paste" "F.Mask")
      (net 135 "unconnected-(U4C-A_SD-PadF8)") (pinfunction "A_SD") (pintype "output+no_connect"))
    (pad "G1" smd circle locked (at -2.275 1.624 270) (size 0.3 0.3) (layers "F.Cu" "F.Paste" "F.Mask")
      (net 138 "/Channel 2/HDMI2_CEC") (pinfunction "CEC") (pintype "bidirectional"))
    (pad "G2" smd circle locked (at -1.625 1.624 270) (size 0.3 0.3) (layers "F.Cu" "F.Paste" "F.Mask")
      (net 33 "Net-(U4B-VDDC1)") (pinfunction "VDDC1") (pintype "power_in"))
    (pad "G3" smd circle locked (at -0.975 1.624 270) (size 0.3 0.3) (layers "F.Cu" "F.Paste" "F.Mask")
      (net 111 "/Channel 2/HDMI2_DDC_SDA_3V3") (pinfunction "DDC_SDA") (pintype "bidirectional"))
    (pad "G4" smd circle locked (at -0.326 1.624 270) (size 0.3 0.3) (layers "F.Cu" "F.Paste" "F.Mask")
      (net 66 "I2C3_SDA") (pinfunction "I2C_SDA") (pintype "bidirectional"))
    (pad "G5" smd circle locked (at 0.325 1.624 270) (size 0.3 0.3) (layers "F.Cu" "F.Paste" "F.Mask")
      (net 107 "/Channel 2/CH2_~{RST}") (pinfunction "~{RESET}") (pintype "input"))
    (pad "G6" smd circle locked (at 0.974 1.624 270) (size 0.3 0.3) (layers "F.Cu" "F.Paste" "F.Mask")
      (net 120 "Net-(U4A-EDID_SDA)") (pinfunction "EDID_SDA") (pintype "bidirectional"))
    (pad "G7" smd circle locked (at 1.624 1.624 270) (size 0.3 0.3) (layers "F.Cu" "F.Paste" "F.Mask")
      (net 136 "unconnected-(U4C-A_WFS-PadG7)") (pinfunction "A_WFS") (pintype "output+no_connect"))
    (pad "G8" smd circle locked (at 2.274 1.624 270) (size 0.3 0.3) (layers "F.Cu" "F.Paste" "F.Mask")
      (net 142 "unconnected-(U4C-A_OSCK-PadG8)") (pinfunction "A_OSCK") (pintype "output+no_connect"))
    (pad "H1" smd circle locked (at -2.275 2.274 270) (size 0.3 0.3) (layers "F.Cu" "F.Paste" "F.Mask")
      (net 119 "/Channel 2/HDMI2_HPDO") (pinfunction "HPDO") (pintype "output"))
    (pad "H2" smd circle locked (at -1.625 2.274 270) (size 0.3 0.3) (layers "F.Cu" "F.Paste" "F.Mask")
      (net 106 "/Channel 2/HDMI2_HPDI") (pinfunction "HPDI") (pintype "input"))
    (pad "H3" smd circle locked (at -0.975 2.274 270) (size 0.3 0.3) (layers "F.Cu" "F.Paste" "F.Mask")
      (net 112 "/Channel 2/HDMI2_DDC_SCL_3V3") (pinfunction "DDC_SCL") (pintype "bidirectional"))
    (pad "H4" smd circle locked (at -0.326 2.274 270) (size 0.3 0.3) (layers "F.Cu" "F.Paste" "F.Mask")
      (net 67 "I2C3_SCL") (pinfunction "I2C_SCL") (pintype "bidirectional"))
    (pad "H5" smd circle locked (at 0.325 2.274 270) (size 0.3 0.3) (layers "F.Cu" "F.Paste" "F.Mask")
      (net 27 "/Channel 2/CH2_REFCLK") (pinfunction "REFCLK") (pintype "input"))
    (pad "H6" smd circle locked (at 0.974 2.274 270) (size 0.3 0.3) (layers "F.Cu" "F.Paste" "F.Mask")
      (net 121 "Net-(U4A-EDID_SCL)") (pinfunction "EDID_SCL") (pintype "bidirectional"))
    (pad "H7" smd circle locked (at 1.624 2.274 270) (size 0.3 0.3) (layers "F.Cu" "F.Paste" "F.Mask")
      (net 26 "Net-(U4B-VDDIO2)") (pinfunction "VDDIO2") (pintype "power_in"))
    (pad "H8" smd circle locked (at 2.274 2.274 270) (size 0.3 0.3) (layers "F.Cu" "F.Paste" "F.Mask")
      (net 2 "GND") (pinfunction "GND") (pintype "passive"))
  )
)
